# T6G (Grand Teton) — schematic netlist excerpt (pin names and nets, part order shuffled) for the footprints in the layout excerpt that follows; sources: Cadence DE-HDL packaged netlist, KiCad conversion of 04192023_DAF0TMB3IC0_F0TG_MB_C_brd_V02_OCP.brd

Q37  MOSFET_NCH_DUAL  PJT138K IC  pkg SOT363XD  page 188
  S1  = GND
  G1  = VR_P5V_EN
  D2  = VR_P5V_EN_D_R1
  S2  = GND
  G2  = VR_P5V_EN_N
  D1  = VR_P5V_EN_N

R461  Q_RES  33 5% CHIP  pkg 0402LF  page 29 : A = SPI_CPU0_CLK ; B = SPI_CPU0_R_CLK

(kicad_pcb
	(version 20260206)
	(generator "pcbnew")
	(generator_version "10.0")
	(general
		(thickness 1.6)
		(legacy_teardrops no)
	)
	(paper "A4")
	(title_block
		(title "04192023_DAF0TMB3IC0_F0TG_MB_C_brd_V02_OCP.brd")
		(comment 1 "Grand Teton / footprints 422-423 of 8354")
	)
	(layers
		(0 "F.Cu" signal "TOP")
		(4 "In1.Cu" signal "GND")
		(6 "In2.Cu" signal "IN1")
		(8 "In3.Cu" signal "GND1")
		(10 "In4.Cu" signal "IN2")
		(12 "In5.Cu" signal "GND2")
		(14 "In6.Cu" signal "IN3")
		(16 "In7.Cu" signal "GND3")
		(18 "In8.Cu" signal "VCC")
		(20 "In9.Cu" signal "VCC1")
		(22 "In10.Cu" signal "GND4")
		(24 "In11.Cu" signal "IN4")
		(26 "In12.Cu" signal "GND5")
		(28 "In13.Cu" signal "IN5")
		(30 "In14.Cu" signal "GND6")
		(32 "In15.Cu" signal "IN6")
		(34 "In16.Cu" signal "GND7")
		(2 "B.Cu" signal "BOTTOM")
		(9 "F.Adhes" user "F.Adhesive")
		(11 "B.Adhes" user "B.Adhesive")
		(13 "F.Paste" user "Package Geometry/Pastemask Top")
		(15 "B.Paste" user "Package Geometry/Pastemask Bottom")
		(5 "F.SilkS" user "Ref Des/Silkscreen Top")
		(7 "B.SilkS" user "Ref Des/Silkscreen Bottom")
		(1 "F.Mask" user "Board Geometry/Soldermask Top")
		(3 "B.Mask" user "Board Geometry/Soldermask Bottom")
		(17 "Dwgs.User" user "User.Drawings")
		(19 "Cmts.User" user "User.Comments")
		(21 "Eco1.User" user "User.Eco1")
		(23 "Eco2.User" user "User.Eco2")
		(25 "Edge.Cuts" user "Board Geometry/Outline")
		(27 "Margin" user)
		(31 "F.CrtYd" user "Package Geometry/Place Bound Top")
		(29 "B.CrtYd" user "Package Geometry/Place Bound Bottom")
		(35 "F.Fab" user "Ref Des/Assembly Top")
		(33 "B.Fab" user "Ref Des/Assembly Bottom")
	)
	(footprint ""
		(layer "F.Cu")
		(at 144.690592 -107.683046 180)
		(property "Reference" "Q37"
			(at 0.715264 1.685036 0)
			(unlocked yes)
			(layer "F.SilkS")
			(effects
				(font
					(size 0.7874 0.5842)
					(thickness 0.1524)
				)
				(justify left)
			)
		)
		(property "Value" ""
			(at 0 0 180)
			(layer "F.Fab")
			(effects
				(font
					(size 1.27 1.27)
				)
			)
		)
		(duplicate_pad_numbers_are_jumpers no)
		(fp_line
			(start 1.332738 1.100074)
			(end -1.332738 1.100074)
			(stroke
				(width 0.1524)
				(type default)
			)
			(layer "F.SilkS")
		)
		(fp_line
			(start 1.332738 -1.100074)
			(end 1.332738 1.100074)
			(stroke
				(width 0.1524)
				(type default)
			)
			(layer "F.SilkS")
		)
		(fp_line
			(start 0.4826 -1.100074)
			(end 1.332738 -1.100074)
			(stroke
				(width 0.1524)
				(type default)
			)
			(layer "F.SilkS")
		)
		(fp_line
			(start 0 -0.541274)
			(end 0.4826 -1.100074)
			(stroke
				(width 0.1524)
				(type default)
			)
			(layer "F.SilkS")
		)
		(fp_line
			(start -0.4826 -1.100074)
			(end 0 -0.541274)
			(stroke
				(width 0.1524)
				(type default)
			)
			(layer "F.SilkS")
		)
		(fp_line
			(start -1.332738 1.100074)
			(end -1.332738 -1.100074)
			(stroke
				(width 0.1524)
				(type default)
			)
			(layer "F.SilkS")
		)
		(fp_line
			(start -1.332738 -1.100074)
			(end -0.4826 -1.100074)
			(stroke
				(width 0.1524)
				(type default)
			)
			(layer "F.SilkS")
		)
		(fp_poly
			(pts
				(xy -1.928876 -0.667512) (xy -2.630932 -0.316484) (xy -2.630932 -1.01854)
			)
			(stroke
				(width 0)
				(type default)
			)
			(fill yes)
			(layer "F.SilkS")
		)
		(fp_line
			(start 0.674878 1.100074)
			(end -0.674878 1.100074)
			(stroke
				(width 0.1)
				(type default)
			)
			(layer "F.Fab")
		)
		(fp_line
			(start 0.674878 -1.100074)
			(end 0.674878 1.100074)
			(stroke
				(width 0.1)
				(type default)
			)
			(layer "F.Fab")
		)
		(fp_line
			(start -0.674878 1.100074)
			(end -0.674878 -1.100074)
			(stroke
				(width 0.1)
				(type default)
			)
			(layer "F.Fab")
		)
		(fp_line
			(start -0.674878 -1.100074)
			(end 0.674878 -1.100074)
			(stroke
				(width 0.1)
				(type default)
			)
			(layer "F.Fab")
		)
		(fp_poly
			(pts
				(xy -2.2352 -0.298958) (xy -2.2352 -1.001014) (xy -1.533144 -0.649986)
			)
			(stroke
				(width 0)
				(type default)
			)
			(fill yes)
			(layer "F.Fab")
		)
		(pad "1" smd rect
			(at -0.94996 -0.649986 270)
			(size 0.4318 0.508)
			(layers "F.Cu" "F.Mask" "F.Paste")
			(net "GND")
		)
		(pad "2" smd rect
			(at -0.94996 0 270)
			(size 0.4318 0.508)
			(layers "F.Cu" "F.Mask" "F.Paste")
			(net "VR_P5V_EN")
		)
		(pad "3" smd rect
			(at -0.94996 0.649986 270)
			(size 0.4318 0.508)
			(layers "F.Cu" "F.Mask" "F.Paste")
			(net "VR_P5V_EN_D_R1")
		)
		(pad "4" smd rect
			(at 0.94996 0.649986 270)
			(size 0.4318 0.508)
			(layers "F.Cu" "F.Mask" "F.Paste")
			(net "GND")
		)
		(pad "5" smd rect
			(at 0.94996 0 270)
			(size 0.4318 0.508)
			(layers "F.Cu" "F.Mask" "F.Paste")
			(net "VR_P5V_EN_N")
		)
		(pad "6" smd rect
			(at 0.94996 -0.649986 270)
			(size 0.4318 0.508)
			(layers "F.Cu" "F.Mask" "F.Paste")
			(net "VR_P5V_EN_N")
		)
	)
	(footprint ""
		(layer "F.Cu")
		(at 402.253958 -324.862952 180)
		(property "Reference" "R461"
			(at 0 0 180)
			(layer "F.SilkS")
			(hide yes)
			(effects
				(font
					(size 1.27 1.27)
				)
			)
		)
		(property "Value" ""
			(at 0 0 180)
			(layer "F.Fab")
			(effects
				(font
					(size 1.27 1.27)
				)
			)
		)
		(duplicate_pad_numbers_are_jumpers no)
		(fp_line
			(start 0.7874 0.4064)
			(end -0.7874 0.4064)
			(stroke
				(width 0.1524)
				(type default)
			)
			(layer "F.SilkS")
		)
		(fp_line
			(start 0.7874 -0.4064)
			(end 0.7874 0.4064)
			(stroke
				(width 0.1524)
				(type default)
			)
			(layer "F.SilkS")
		)
		(fp_line
			(start -0.7874 0.4064)
			(end -0.7874 -0.4064)
			(stroke
				(width 0.1524)
				(type default)
			)
			(layer "F.SilkS")
		)
		(fp_line
			(start -0.7874 -0.4064)
			(end 0.7874 -0.4064)
			(stroke
				(width 0.1524)
				(type default)
			)
			(layer "F.SilkS")
		)
		(fp_line
			(start 0.67945 0.3048)
			(end 0.120396 0.3048)
			(stroke
				(width 0.1)
				(type default)
			)
			(layer "F.Fab")
		)
		(fp_line
			(start 0.67945 -0.3048)
			(end 0.67945 0.3048)
			(stroke
				(width 0.1)
				(type default)
			)
			(layer "F.Fab")
		)
		(fp_line
			(start 0.12065 -0.2794)
			(end 0.12065 -0.3048)
			(stroke
				(width 0.1)
				(type default)
			)
			(layer "F.Fab")
		)
		(fp_line
			(start 0.12065 -0.3048)
			(end 0.67945 -0.3048)
			(stroke
				(width 0.1)
				(type default)
			)
			(layer "F.Fab")
		)
		(fp_line
			(start 0.120396 0.3048)
			(end 0.120396 0.2794)
			(stroke
				(width 0.1)
				(type default)
			)
			(layer "F.Fab")
		)
		(fp_line
			(start 0.120396 0.2794)
			(end -0.12065 0.2794)
			(stroke
				(width 0.1)
				(type default)
			)
			(layer "F.Fab")
		)
		(fp_line
			(start -0.12065 0.3048)
			(end -0.67945 0.3048)
			(stroke
				(width 0.1)
				(type default)
			)
			(layer "F.Fab")
		)
		(fp_line
			(start -0.12065 0.2794)
			(end -0.12065 0.3048)
			(stroke
				(width 0.1)
				(type default)
			)
			(layer "F.Fab")
		)
		(fp_line
			(start -0.12065 -0.2794)
			(end 0.12065 -0.2794)
			(stroke
				(width 0.1)
				(type default)
			)
			(layer "F.Fab")
		)
		(fp_line
			(start -0.12065 -0.305054)
			(end -0.12065 -0.2794)
			(stroke
				(width 0.1)
				(type default)
			)
			(layer "F.Fab")
		)
		(fp_line
			(start -0.67945 0.3048)
			(end -0.67945 -0.305054)
			(stroke
				(width 0.1)
				(type default)
			)
			(layer "F.Fab")
		)
		(fp_line
			(start -0.67945 -0.305054)
			(end -0.12065 -0.305054)
			(stroke
				(width 0.1)
				(type default)
			)
			(layer "F.Fab")
		)
		(pad "1" smd circle
			(at -0.40005 0 180)
			(size 0 0)
			(layers "F.Cu" "F.Mask" "F.Paste")
			(net "SPI_CPU0_CLK")
		)
		(pad "2" smd circle
			(at 0.40005 0 180)
			(size 0 0)
			(layers "F.Cu" "F.Mask" "F.Paste")
			(net "SPI_CPU0_R_CLK")
		)
	)
)
